(kicad_pcb
	(version 20260206)
	(generator "pcbnew")
	(generator_version "10.0")
	(general
		(thickness 1.6)
		(legacy_teardrops no)
	)
	(paper "A4")
	(title_block
		(title "Bryce Canyon_SCC_16316-1_OCP.brd")
		(comment 1 "Bryce Canyon / footprints 1472-1479 of 1561")
	)
	(layers
		(0 "F.Cu" signal "TOP")
		(4 "In1.Cu" signal "L2GND")
		(6 "In2.Cu" signal "L3")
		(8 "In3.Cu" signal "L4VCC")
		(10 "In4.Cu" signal "L5VCC")
		(12 "In5.Cu" signal "L6")
		(14 "In6.Cu" signal "L7GND")
		(2 "B.Cu" signal "BOTTOM")
		(9 "F.Adhes" user "F.Adhesive")
		(11 "B.Adhes" user "B.Adhesive")
		(13 "F.Paste" user "Package Geometry/Pastemask Top")
		(15 "B.Paste" user "Package Geometry/Pastemask Bottom")
		(5 "F.SilkS" user "Ref Des/Silkscreen Top")
		(7 "B.SilkS" user "Ref Des/Silkscreen Bottom")
		(1 "F.Mask" user "Board Geometry/Soldermask Top")
		(3 "B.Mask" user "Board Geometry/Soldermask Bottom")
		(17 "Dwgs.User" user "User.Drawings")
		(19 "Cmts.User" user "User.Comments")
		(21 "Eco1.User" user "User.Eco1")
		(23 "Eco2.User" user "User.Eco2")
		(25 "Edge.Cuts" user "Board Geometry/Outline")
		(27 "Margin" user)
		(31 "F.CrtYd" user "Package Geometry/Place Bound Top")
		(29 "B.CrtYd" user "Package Geometry/Place Bound Bottom")
		(35 "F.Fab" user "Ref Des/Assembly Top")
		(33 "B.Fab" user "Ref Des/Assembly Bottom")
	)
	(footprint ""
		(layer "B.Cu")
		(at 166.6748 -60.5536 90)
		(property "Reference" "C354"
			(at 0 0 90)
			(layer "B.SilkS")
			(hide yes)
			(effects
				(font
					(size 1.27 1.27)
				)
				(justify mirror)
			)
		)
		(property "Value" "SCD1U16V2KX-3GP"
			(at -1.1811 -2.7051 90)
			(unlocked yes)
			(layer "B.Fab")
			(hide yes)
			(effects
				(font
					(size 1.016 1.016)
					(thickness 0.1524)
				)
				(justify mirror)
			)
		)
		(property "Device Type" "C402H22"
			(at -1.1811 -4.2291 90)
			(unlocked yes)
			(layer "B.Fab")
			(hide yes)
			(effects
				(font
					(size 1.016 1.016)
					(thickness 0.1524)
				)
				(justify mirror)
			)
		)
		(duplicate_pad_numbers_are_jumpers no)
		(fp_rect
			(start 0.4318 0.9525)
			(end -0.4318 -0.9525)
			(stroke
				(width 0)
				(type default)
			)
			(fill no)
			(layer "B.CrtYd")
		)
		(fp_rect
			(start 0.4318 0.9525)
			(end -0.4318 -0.9525)
			(stroke
				(width 0)
				(type default)
			)
			(fill no)
			(layer "B.Fab")
		)
		(pad "1" smd custom
			(at 0 -0.4445 270)
			(size 0.1524 0.1524)
			(layers "B.Cu" "B.Mask" "B.Paste")
			(net "HM40ADC_VDDA")
			(options
				(clearance outline)
				(anchor circle)
			)
			(primitives
				(gr_poly
					(pts
						(arc
							(start 0.3048 0.2032)
							(mid 0.275042 0.275042)
							(end 0.2032 0.3048)
						)
						(arc
							(start -0.2032 0.3048)
							(mid -0.275042 0.275042)
							(end -0.3048 0.2032)
						)
						(arc
							(start -0.3048 -0.2032)
							(mid -0.275042 -0.275042)
							(end -0.2032 -0.3048)
						)
						(arc
							(start 0.2032 -0.3048)
							(mid 0.275042 -0.275042)
							(end 0.3048 -0.2032)
						)
					)
					(width 0)
					(fill yes)
				)
			)
		)
		(pad "2" smd custom
			(at 0 0.4445 270)
			(size 0.1524 0.1524)
			(layers "B.Cu" "B.Mask" "B.Paste")
			(net "GND")
			(options
				(clearance outline)
				(anchor circle)
			)
			(primitives
				(gr_poly
					(pts
						(arc
							(start 0.3048 0.2032)
							(mid 0.275042 0.275042)
							(end 0.2032 0.3048)
						)
						(arc
							(start -0.2032 0.3048)
							(mid -0.275042 0.275042)
							(end -0.3048 0.2032)
						)
						(arc
							(start -0.3048 -0.2032)
							(mid -0.275042 -0.275042)
							(end -0.2032 -0.3048)
						)
						(arc
							(start 0.2032 -0.3048)
							(mid 0.275042 -0.275042)
							(end 0.3048 -0.2032)
						)
					)
					(width 0)
					(fill yes)
				)
			)
		)
	)
	(footprint ""
		(layer "B.Cu")
		(at 164.923978 -20.583144)
		(property "Reference" "C311"
			(at 0 0 0)
			(layer "B.SilkS")
			(hide yes)
			(effects
				(font
					(size 1.27 1.27)
				)
				(justify mirror)
			)
		)
		(property "Value" "SCD22U10V1KX-GP"
			(at 2.8321 -1.7399 0)
			(unlocked yes)
			(layer "B.Fab")
			(hide yes)
			(effects
				(font
					(size 1.016 1.016)
					(thickness 0.1524)
				)
				(justify mirror)
			)
		)
		(property "Device Type" "C0201H13"
			(at 2.8321 -3.2639 0)
			(unlocked yes)
			(layer "B.Fab")
			(hide yes)
			(effects
				(font
					(size 1.016 1.016)
					(thickness 0.1524)
				)
				(justify mirror)
			)
		)
		(duplicate_pad_numbers_are_jumpers no)
		(fp_rect
			(start 0.2794 0.6477)
			(end -0.2794 -0.6477)
			(stroke
				(width 0)
				(type default)
			)
			(fill no)
			(layer "B.CrtYd")
		)
		(fp_rect
			(start 0.2794 0.6477)
			(end -0.2794 -0.6477)
			(stroke
				(width 0)
				(type default)
			)
			(fill no)
			(layer "B.Fab")
		)
		(pad "1" smd custom
			(at 0 -0.2794 180)
			(size 0.0762 0.0762)
			(layers "B.Cu" "B.Mask" "B.Paste")
			(net "PCIE_SCC_TO_COMP_C_0_DP")
			(options
				(clearance outline)
				(anchor circle)
			)
			(primitives
				(gr_poly
					(pts
						(arc
							(start 0.1524 0.127)
							(mid 0.137521 0.162921)
							(end 0.1016 0.1778)
						)
						(arc
							(start -0.1016 0.1778)
							(mid -0.137521 0.162921)
							(end -0.1524 0.127)
						)
						(arc
							(start -0.1524 -0.127)
							(mid -0.137521 -0.162921)
							(end -0.1016 -0.1778)
						)
						(arc
							(start 0.1016 -0.1778)
							(mid 0.137521 -0.162921)
							(end 0.1524 -0.127)
						)
					)
					(width 0)
					(fill yes)
				)
			)
		)
		(pad "2" smd custom
			(at 0 0.2794 180)
			(size 0.0762 0.0762)
			(layers "B.Cu" "B.Mask" "B.Paste")
			(net "PCIE_SCC_TO_COMP_0_DP")
			(options
				(clearance outline)
				(anchor circle)
			)
			(primitives
				(gr_poly
					(pts
						(arc
							(start 0.1524 0.127)
							(mid 0.137521 0.162921)
							(end 0.1016 0.1778)
						)
						(arc
							(start -0.1016 0.1778)
							(mid -0.137521 0.162921)
							(end -0.1524 0.127)
						)
						(arc
							(start -0.1524 -0.127)
							(mid -0.137521 -0.162921)
							(end -0.1016 -0.1778)
						)
						(arc
							(start 0.1016 -0.1778)
							(mid 0.137521 -0.162921)
							(end 0.1524 -0.127)
						)
					)
					(width 0)
					(fill yes)
				)
			)
		)
	)
	(footprint ""
		(layer "B.Cu")
		(at 131.8768 -117.4496 -90)
		(property "Reference" "C690"
			(at 0 0 90)
			(layer "B.SilkS")
			(hide yes)
			(effects
				(font
					(size 1.27 1.27)
				)
				(justify mirror)
			)
		)
		(property "Value" "SC10U6D3V5KX-4GP"
			(at 0.0762 -6.1214 270)
			(unlocked yes)
			(layer "B.Fab")
			(hide yes)
			(effects
				(font
					(size 1.016 1.016)
					(thickness 0.1524)
				)
				(justify mirror)
			)
		)
		(property "Device Type" "C805H58"
			(at 0.0762 -8.1534 270)
			(unlocked yes)
			(layer "B.Fab")
			(hide yes)
			(effects
				(font
					(size 1.016 1.016)
					(thickness 0.1524)
				)
				(justify mirror)
			)
		)
		(duplicate_pad_numbers_are_jumpers no)
		(fp_line
			(start -0.635 0)
			(end 0.635 0)
			(stroke
				(width 0.508)
				(type default)
			)
			(layer "B.SilkS")
		)
		(fp_rect
			(start 0.9652 1.778)
			(end -0.9652 -1.778)
			(stroke
				(width 0)
				(type default)
			)
			(fill no)
			(layer "B.CrtYd")
		)
		(fp_poly
			(pts
				(xy 0.9652 -1.778) (xy -0.9652 -1.778) (xy -0.9652 1.778) (xy 0.9652 1.778)
			)
			(stroke
				(width 0)
				(type default)
			)
			(fill no)
			(layer "B.Fab")
		)
		(pad "1" smd rect
			(at 0 -0.9652 90)
			(size 1.397 1.143)
			(layers "B.Cu" "B.Mask" "B.Paste")
			(net "P1V5_C")
		)
		(pad "2" smd rect
			(at 0 0.9652 90)
			(size 1.397 1.143)
			(layers "B.Cu" "B.Mask" "B.Paste")
			(net "GND")
		)
	)
	(footprint ""
		(layer "B.Cu")
		(at 124.714 -67.4624 90)
		(property "Reference" "C300"
			(at 0 0 90)
			(layer "B.SilkS")
			(hide yes)
			(effects
				(font
					(size 1.27 1.27)
				)
				(justify mirror)
			)
		)
		(property "Value" "SCD1U6D3V1KX-GP"
			(at 2.8321 -1.7399 90)
			(unlocked yes)
			(layer "B.Fab")
			(hide yes)
			(effects
				(font
					(size 1.016 1.016)
					(thickness 0.1524)
				)
				(justify mirror)
			)
		)
		(property "Device Type" "C0201H13"
			(at 2.8321 -3.2639 90)
			(unlocked yes)
			(layer "B.Fab")
			(hide yes)
			(effects
				(font
					(size 1.016 1.016)
					(thickness 0.1524)
				)
				(justify mirror)
			)
		)
		(duplicate_pad_numbers_are_jumpers no)
		(fp_rect
			(start 0.2794 0.6477)
			(end -0.2794 -0.6477)
			(stroke
				(width 0)
				(type default)
			)
			(fill no)
			(layer "B.CrtYd")
		)
		(fp_rect
			(start 0.2794 0.6477)
			(end -0.2794 -0.6477)
			(stroke
				(width 0)
				(type default)
			)
			(fill no)
			(layer "B.Fab")
		)
		(pad "1" smd custom
			(at 0 -0.2794 270)
			(size 0.0762 0.0762)
			(layers "B.Cu" "B.Mask" "B.Paste")
			(net "GB_VDDA")
			(options
				(clearance outline)
				(anchor circle)
			)
			(primitives
				(gr_poly
					(pts
						(arc
							(start 0.1524 0.127)
							(mid 0.137521 0.162921)
							(end 0.1016 0.1778)
						)
						(arc
							(start -0.1016 0.1778)
							(mid -0.137521 0.162921)
							(end -0.1524 0.127)
						)
						(arc
							(start -0.1524 -0.127)
							(mid -0.137521 -0.162921)
							(end -0.1016 -0.1778)
						)
						(arc
							(start 0.1016 -0.1778)
							(mid 0.137521 -0.162921)
							(end 0.1524 -0.127)
						)
					)
					(width 0)
					(fill yes)
				)
			)
		)
		(pad "2" smd custom
			(at 0 0.2794 270)
			(size 0.0762 0.0762)
			(layers "B.Cu" "B.Mask" "B.Paste")
			(net "GND")
			(options
				(clearance outline)
				(anchor circle)
			)
			(primitives
				(gr_poly
					(pts
						(arc
							(start 0.1524 0.127)
							(mid 0.137521 0.162921)
							(end 0.1016 0.1778)
						)
						(arc
							(start -0.1016 0.1778)
							(mid -0.137521 0.162921)
							(end -0.1524 0.127)
						)
						(arc
							(start -0.1524 -0.127)
							(mid -0.137521 -0.162921)
							(end -0.1016 -0.1778)
						)
						(arc
							(start 0.1016 -0.1778)
							(mid 0.137521 -0.162921)
							(end 0.1524 -0.127)
						)
					)
					(width 0)
					(fill yes)
				)
			)
		)
	)
	(footprint ""
		(layer "B.Cu")
		(at 104.4575 -83.8835 90)
		(property "Reference" "R35"
			(at 0 0 90)
			(layer "B.SilkS")
			(hide yes)
			(effects
				(font
					(size 1.27 1.27)
				)
				(justify mirror)
			)
		)
		(property "Value" "4K75R2F-1-GP"
			(at -0.064008 -3.993896 90)
			(unlocked yes)
			(layer "B.Fab")
			(hide yes)
			(effects
				(font
					(size 1.016 1.016)
					(thickness 0.1524)
				)
				(justify mirror)
			)
		)
		(property "Device Type" "R402H16"
			(at -0.064008 -5.517896 90)
			(unlocked yes)
			(layer "B.Fab")
			(hide yes)
			(effects
				(font
					(size 1.016 1.016)
					(thickness 0.1524)
				)
				(justify mirror)
			)
		)
		(duplicate_pad_numbers_are_jumpers no)
		(fp_line
			(start 0.508 -0.9398)
			(end 0.508 0.9398)
			(stroke
				(width 0.1524)
				(type default)
			)
			(layer "B.SilkS")
		)
		(fp_line
			(start -0.508 -0.9398)
			(end 0.508 -0.9398)
			(stroke
				(width 0.1524)
				(type default)
			)
			(layer "B.SilkS")
		)
		(fp_rect
			(start 0.508 0.9398)
			(end -0.508 -0.9398)
			(stroke
				(width 0)
				(type default)
			)
			(fill no)
			(layer "B.CrtYd")
		)
		(fp_rect
			(start 0.508 0.9398)
			(end -0.508 -0.9398)
			(stroke
				(width 0)
				(type default)
			)
			(fill no)
			(layer "B.Fab")
		)
		(pad "1" smd custom
			(at 0 -0.4445 270)
			(size 0.1397 0.1397)
			(layers "B.Cu" "B.Mask" "B.Paste")
			(net "GND")
			(options
				(clearance outline)
				(anchor circle)
			)
			(primitives
				(gr_poly
					(pts
						(arc
							(start -0.1778 0.2794)
							(mid -0.249642 0.249642)
							(end -0.2794 0.1778)
						)
						(arc
							(start -0.2794 -0.1778)
							(mid -0.249642 -0.249642)
							(end -0.1778 -0.2794)
						)
						(arc
							(start 0.1778 -0.2794)
							(mid 0.249642 -0.249642)
							(end 0.2794 -0.1778)
						)
						(arc
							(start 0.2794 0.1778)
							(mid 0.249642 0.249642)
							(end 0.1778 0.2794)
						)
					)
					(width 0)
					(fill yes)
				)
			)
		)
		(pad "2" smd custom
			(at 0 0.4445 270)
			(size 0.1397 0.1397)
			(layers "B.Cu" "B.Mask" "B.Paste")
			(net "EXP_ADC_IN0")
			(options
				(clearance outline)
				(anchor circle)
			)
			(primitives
				(gr_poly
					(pts
						(arc
							(start -0.1778 0.2794)
							(mid -0.249642 0.249642)
							(end -0.2794 0.1778)
						)
						(arc
							(start -0.2794 -0.1778)
							(mid -0.249642 -0.249642)
							(end -0.1778 -0.2794)
						)
						(arc
							(start 0.1778 -0.2794)
							(mid 0.249642 -0.249642)
							(end 0.2794 -0.1778)
						)
						(arc
							(start 0.2794 0.1778)
							(mid 0.249642 0.249642)
							(end 0.1778 0.2794)
						)
					)
					(width 0)
					(fill yes)
				)
			)
		)
	)
	(footprint ""
		(layer "B.Cu")
		(at 96.134936 -78.955138 -90)
		(property "Reference" "R207"
			(at 0 0 90)
			(layer "B.SilkS")
			(hide yes)
			(effects
				(font
					(size 1.27 1.27)
				)
				(justify mirror)
			)
		)
		(property "Value" "0R2J-2-GP"
			(at -0.064008 -3.993896 270)
			(unlocked yes)
			(layer "B.Fab")
			(hide yes)
			(effects
				(font
					(size 1.016 1.016)
					(thickness 0.1524)
				)
				(justify mirror)
			)
		)
		(property "Device Type" "R402H16"
			(at -0.064008 -5.517896 270)
			(unlocked yes)
			(layer "B.Fab")
			(hide yes)
			(effects
				(font
					(size 1.016 1.016)
					(thickness 0.1524)
				)
				(justify mirror)
			)
		)
		(duplicate_pad_numbers_are_jumpers no)
		(fp_line
			(start -0.508 -0.9398)
			(end 0.508 -0.9398)
			(stroke
				(width 0.1524)
				(type default)
			)
			(layer "B.SilkS")
		)
		(fp_line
			(start 0.508 -0.9398)
			(end 0.508 0.9398)
			(stroke
				(width 0.1524)
				(type default)
			)
			(layer "B.SilkS")
		)
		(fp_rect
			(start 0.508 0.9398)
			(end -0.508 -0.9398)
			(stroke
				(width 0)
				(type default)
			)
			(fill no)
			(layer "B.CrtYd")
		)
		(fp_rect
			(start 0.508 0.9398)
			(end -0.508 -0.9398)
			(stroke
				(width 0)
				(type default)
			)
			(fill no)
			(layer "B.Fab")
		)
		(pad "1" smd custom
			(at 0 -0.4445 90)
			(size 0.1397 0.1397)
			(layers "B.Cu" "B.Mask" "B.Paste")
			(net "FW_RESET_N")
			(options
				(clearance outline)
				(anchor circle)
			)
			(primitives
				(gr_poly
					(pts
						(arc
							(start -0.1778 0.2794)
							(mid -0.249642 0.249642)
							(end -0.2794 0.1778)
						)
						(arc
							(start -0.2794 -0.1778)
							(mid -0.249642 -0.249642)
							(end -0.1778 -0.2794)
						)
						(arc
							(start 0.1778 -0.2794)
							(mid 0.249642 -0.249642)
							(end 0.2794 -0.1778)
						)
						(arc
							(start 0.2794 0.1778)
							(mid 0.249642 0.249642)
							(end 0.1778 0.2794)
						)
					)
					(width 0)
					(fill yes)
				)
			)
		)
		(pad "2" smd custom
			(at 0 0.4445 90)
			(size 0.1397 0.1397)
			(layers "B.Cu" "B.Mask" "B.Paste")
			(net "EXP_SYS_RST_N")
			(options
				(clearance outline)
				(anchor circle)
			)
			(primitives
				(gr_poly
					(pts
						(arc
							(start -0.1778 0.2794)
							(mid -0.249642 0.249642)
							(end -0.2794 0.1778)
						)
						(arc
							(start -0.2794 -0.1778)
							(mid -0.249642 -0.249642)
							(end -0.1778 -0.2794)
						)
						(arc
							(start 0.1778 -0.2794)
							(mid 0.249642 -0.249642)
							(end 0.2794 -0.1778)
						)
						(arc
							(start 0.2794 0.1778)
							(mid 0.249642 0.249642)
							(end 0.1778 0.2794)
						)
					)
					(width 0)
					(fill yes)
				)
			)
		)
	)
	(footprint ""
		(layer "B.Cu")
		(at 176.1998 -38.1127 90)
		(property "Reference" "C429"
			(at 0 0 90)
			(layer "B.SilkS")
			(hide yes)
			(effects
				(font
					(size 1.27 1.27)
				)
				(justify mirror)
			)
		)
		(property "Value" "SCD1U6D3V1KX-GP"
			(at 2.8321 -1.7399 90)
			(unlocked yes)
			(layer "B.Fab")
			(hide yes)
			(effects
				(font
					(size 1.016 1.016)
					(thickness 0.1524)
				)
				(justify mirror)
			)
		)
		(property "Device Type" "C0201H13"
			(at 2.8321 -3.2639 90)
			(unlocked yes)
			(layer "B.Fab")
			(hide yes)
			(effects
				(font
					(size 1.016 1.016)
					(thickness 0.1524)
				)
				(justify mirror)
			)
		)
		(duplicate_pad_numbers_are_jumpers no)
		(fp_rect
			(start 0.2794 0.6477)
			(end -0.2794 -0.6477)
			(stroke
				(width 0)
				(type default)
			)
			(fill no)
			(layer "B.CrtYd")
		)
		(fp_rect
			(start 0.2794 0.6477)
			(end -0.2794 -0.6477)
			(stroke
				(width 0)
				(type default)
			)
			(fill no)
			(layer "B.Fab")
		)
		(pad "1" smd custom
			(at 0 -0.2794 270)
			(size 0.0762 0.0762)
			(layers "B.Cu" "B.Mask" "B.Paste")
			(net "P0V975")
			(options
				(clearance outline)
				(anchor circle)
			)
			(primitives
				(gr_poly
					(pts
						(arc
							(start 0.1524 0.127)
							(mid 0.137521 0.162921)
							(end 0.1016 0.1778)
						)
						(arc
							(start -0.1016 0.1778)
							(mid -0.137521 0.162921)
							(end -0.1524 0.127)
						)
						(arc
							(start -0.1524 -0.127)
							(mid -0.137521 -0.162921)
							(end -0.1016 -0.1778)
						)
						(arc
							(start 0.1016 -0.1778)
							(mid 0.137521 -0.162921)
							(end 0.1524 -0.127)
						)
					)
					(width 0)
					(fill yes)
				)
			)
		)
		(pad "2" smd custom
			(at 0 0.2794 270)
			(size 0.0762 0.0762)
			(layers "B.Cu" "B.Mask" "B.Paste")
			(net "GND")
			(options
				(clearance outline)
				(anchor circle)
			)
			(primitives
				(gr_poly
					(pts
						(arc
							(start 0.1524 0.127)
							(mid 0.137521 0.162921)
							(end 0.1016 0.1778)
						)
						(arc
							(start -0.1016 0.1778)
							(mid -0.137521 0.162921)
							(end -0.1524 0.127)
						)
						(arc
							(start -0.1524 -0.127)
							(mid -0.137521 -0.162921)
							(end -0.1016 -0.1778)
						)
						(arc
							(start 0.1016 -0.1778)
							(mid 0.137521 -0.162921)
							(end 0.1524 -0.127)
						)
					)
					(width 0)
					(fill yes)
				)
			)
		)
	)
	(footprint ""
		(layer "B.Cu")
		(at 176.202848 -41.31691 90)
		(property "Reference" "C431"
			(at 0 0 90)
			(layer "B.SilkS")
			(hide yes)
			(effects
				(font
					(size 1.27 1.27)
				)
				(justify mirror)
			)
		)
		(property "Value" "SCD1U6D3V1KX-GP"
			(at 2.8321 -1.7399 90)
			(unlocked yes)
			(layer "B.Fab")
			(hide yes)
			(effects
				(font
					(size 1.016 1.016)
					(thickness 0.1524)
				)
				(justify mirror)
			)
		)
		(property "Device Type" "C0201H13"
			(at 2.8321 -3.2639 90)
			(unlocked yes)
			(layer "B.Fab")
			(hide yes)
			(effects
				(font
					(size 1.016 1.016)
					(thickness 0.1524)
				)
				(justify mirror)
			)
		)
		(duplicate_pad_numbers_are_jumpers no)
		(fp_rect
			(start 0.2794 0.6477)
			(end -0.2794 -0.6477)
			(stroke
				(width 0)
				(type default)
			)
			(fill no)
			(layer "B.CrtYd")
		)
		(fp_rect
			(start 0.2794 0.6477)
			(end -0.2794 -0.6477)
			(stroke
				(width 0)
				(type default)
			)
			(fill no)
			(layer "B.Fab")
		)
		(pad "1" smd custom
			(at 0 -0.2794 270)
			(size 0.0762 0.0762)
			(layers "B.Cu" "B.Mask" "B.Paste")
			(net "P0V975")
			(options
				(clearance outline)
				(anchor circle)
			)
			(primitives
				(gr_poly
					(pts
						(arc
							(start 0.1524 0.127)
							(mid 0.137521 0.162921)
							(end 0.1016 0.1778)
						)
						(arc
							(start -0.1016 0.1778)
							(mid -0.137521 0.162921)
							(end -0.1524 0.127)
						)
						(arc
							(start -0.1524 -0.127)
							(mid -0.137521 -0.162921)
							(end -0.1016 -0.1778)
						)
						(arc
							(start 0.1016 -0.1778)
							(mid 0.137521 -0.162921)
							(end 0.1524 -0.127)
						)
					)
					(width 0)
					(fill yes)
				)
			)
		)
		(pad "2" smd custom
			(at 0 0.2794 270)
			(size 0.0762 0.0762)
			(layers "B.Cu" "B.Mask" "B.Paste")
			(net "GND")
			(options
				(clearance outline)
				(anchor circle)
			)
			(primitives
				(gr_poly
					(pts
						(arc
							(start 0.1524 0.127)
							(mid 0.137521 0.162921)
							(end 0.1016 0.1778)
						)
						(arc
							(start -0.1016 0.1778)
							(mid -0.137521 0.162921)
							(end -0.1524 0.127)
						)
						(arc
							(start -0.1524 -0.127)
							(mid -0.137521 -0.162921)
							(end -0.1016 -0.1778)
						)
						(arc
							(start 0.1016 -0.1778)
							(mid 0.137521 -0.162921)
							(end 0.1524 -0.127)
						)
					)
					(width 0)
					(fill yes)
				)
			)
		)
	)
)
